(kicad_pcb
	(version 20260206)
	(generator "pcbnew")
	(generator_version "10.0")
	(general
		(thickness 1.6)
		(legacy_teardrops no)
	)
	(paper "A4")
	(title_block
		(title "Wiwynn_Tioga_Pass_MB.brd")
		(comment 1 "Tioga Pass / footprints 2241-2247 of 4770")
	)
	(layers
		(0 "F.Cu" signal "TOP")
		(4 "In1.Cu" signal "L2GND")
		(6 "In2.Cu" signal "L3")
		(8 "In3.Cu" signal "L4GND")
		(10 "In4.Cu" signal "L5")
		(12 "In5.Cu" signal "L6GND")
		(14 "In6.Cu" signal "L7VCC")
		(16 "In7.Cu" signal "L8VCC")
		(18 "In8.Cu" signal "L9GND")
		(20 "In9.Cu" signal "L10")
		(22 "In10.Cu" signal "L11GND")
		(24 "In11.Cu" signal "L12")
		(26 "In12.Cu" signal "L13GND")
		(2 "B.Cu" signal "BOTTOM")
		(9 "F.Adhes" user "F.Adhesive")
		(11 "B.Adhes" user "B.Adhesive")
		(13 "F.Paste" user "Package Geometry/Pastemask Top")
		(15 "B.Paste" user "Package Geometry/Pastemask Bottom")
		(5 "F.SilkS" user "Ref Des/Silkscreen Top")
		(7 "B.SilkS" user "Ref Des/Silkscreen Bottom")
		(1 "F.Mask" user "Board Geometry/Soldermask Top")
		(3 "B.Mask" user "Board Geometry/Soldermask Bottom")
		(17 "Dwgs.User" user "User.Drawings")
		(19 "Cmts.User" user "User.Comments")
		(21 "Eco1.User" user "User.Eco1")
		(23 "Eco2.User" user "User.Eco2")
		(25 "Edge.Cuts" user "Board Geometry/Outline")
		(27 "Margin" user)
		(31 "F.CrtYd" user "Package Geometry/Place Bound Top")
		(29 "B.CrtYd" user "Package Geometry/Place Bound Bottom")
		(35 "F.Fab" user "Ref Des/Assembly Top")
		(33 "B.Fab" user "Ref Des/Assembly Bottom")
	)
	(footprint ""
		(layer "F.Cu")
		(at 13.54836 4.266184)
		(property "Reference" "C1G25"
			(at 0 0 0)
			(layer "F.SilkS")
			(hide yes)
			(effects
				(font
					(size 1.27 1.27)
				)
			)
		)
		(property "Value" ""
			(at 0 0 0)
			(layer "F.Fab")
			(effects
				(font
					(size 1.27 1.27)
				)
			)
		)
		(duplicate_pad_numbers_are_jumpers no)
		(fp_rect
			(start 0.3048 -0.1016)
			(end -0.3048 0.9906)
			(stroke
				(width 0)
				(type default)
			)
			(fill no)
			(layer "F.CrtYd")
		)
		(fp_line
			(start -0.3048 -0.1016)
			(end -0.3048 0.9906)
			(stroke
				(width 0.1)
				(type default)
			)
			(layer "F.Fab")
		)
		(fp_line
			(start -0.3048 0.9906)
			(end 0.3048 0.9906)
			(stroke
				(width 0.1)
				(type default)
			)
			(layer "F.Fab")
		)
		(fp_line
			(start 0.3048 -0.1016)
			(end -0.3048 -0.1016)
			(stroke
				(width 0.1)
				(type default)
			)
			(layer "F.Fab")
		)
		(fp_line
			(start 0.3048 0.9906)
			(end 0.3048 -0.1016)
			(stroke
				(width 0.1)
				(type default)
			)
			(layer "F.Fab")
		)
		(pad "1" smd rect
			(at 0 0)
			(size 0.508 0.508)
			(layers "F.Cu" "F.Mask" "F.Paste")
			(net "VR_PVDDQ_GHJ_VDD")
		)
		(pad "2" smd rect
			(at 0 0.889)
			(size 0.508 0.508)
			(layers "F.Cu" "F.Mask" "F.Paste")
			(net "GND")
		)
		(zone
			(layer "F.Cu")
			(hatch none 0.5)
			(connect_pads
				(clearance 0)
			)
			(min_thickness 0.25)
			(keepout
				(tracks not_allowed)
				(vias allowed)
				(pads allowed)
				(copperpour not_allowed)
				(footprints allowed)
			)
			(placement
				(enabled no)
				(sheetname "")
			)
			(fill
				(thermal_gap 0.5)
				(thermal_bridge_width 0.5)
				(island_removal_mode 0)
			)
			(polygon
				(pts
					(xy 13.80236 4.520184) (xy 13.29436 4.520184) (xy 13.29436 4.901184) (xy 13.80236 4.901184)
				)
			)
		)
		(zone
			(layer "F.Cu")
			(hatch none 0.5)
			(connect_pads
				(clearance 0)
			)
			(min_thickness 0.25)
			(keepout
				(tracks allowed)
				(vias not_allowed)
				(pads allowed)
				(copperpour not_allowed)
				(footprints allowed)
			)
			(placement
				(enabled no)
				(sheetname "")
			)
			(fill
				(thermal_gap 0.5)
				(thermal_bridge_width 0.5)
				(island_removal_mode 0)
			)
			(polygon
				(pts
					(xy 13.80236 4.520184) (xy 13.29436 4.520184) (xy 13.29436 4.901184) (xy 13.80236 4.901184)
				)
			)
		)
	)
	(footprint ""
		(layer "F.Cu")
		(at 23.114 -78.613 -90)
		(property "Reference" "R1D29"
			(at 0 0 270)
			(layer "F.SilkS")
			(hide yes)
			(effects
				(font
					(size 1.27 1.27)
				)
			)
		)
		(property "Value" ""
			(at 0 0 270)
			(layer "F.Fab")
			(effects
				(font
					(size 1.27 1.27)
				)
			)
		)
		(duplicate_pad_numbers_are_jumpers no)
		(fp_rect
			(start -0.2794 -0.1016)
			(end 0.2794 0.9906)
			(stroke
				(width 0)
				(type default)
			)
			(fill no)
			(layer "F.CrtYd")
		)
		(fp_line
			(start -0.2794 0.9906)
			(end 0.2794 0.9906)
			(stroke
				(width 0.1)
				(type default)
			)
			(layer "F.Fab")
		)
		(fp_line
			(start 0.2794 0.9906)
			(end 0.2794 -0.1016)
			(stroke
				(width 0.1)
				(type default)
			)
			(layer "F.Fab")
		)
		(fp_line
			(start -0.2794 -0.1016)
			(end -0.2794 0.9906)
			(stroke
				(width 0.1)
				(type default)
			)
			(layer "F.Fab")
		)
		(fp_line
			(start 0.2794 -0.1016)
			(end -0.2794 -0.1016)
			(stroke
				(width 0.1)
				(type default)
			)
			(layer "F.Fab")
		)
		(pad "1" smd rect
			(at 0 0 270)
			(size 0.508 0.508)
			(layers "F.Cu" "F.Mask" "F.Paste")
			(net "A_HSC_VCAP")
		)
		(pad "2" smd rect
			(at 0 0.889 270)
			(size 0.508 0.508)
			(layers "F.Cu" "F.Mask" "F.Paste")
			(net "FM_P12V_HSC_ADR1")
		)
		(zone
			(layer "F.Cu")
			(hatch none 0.5)
			(connect_pads
				(clearance 0)
			)
			(min_thickness 0.25)
			(keepout
				(tracks allowed)
				(vias not_allowed)
				(pads allowed)
				(copperpour not_allowed)
				(footprints allowed)
			)
			(placement
				(enabled no)
				(sheetname "")
			)
			(fill
				(thermal_gap 0.5)
				(thermal_bridge_width 0.5)
				(island_removal_mode 0)
			)
			(polygon
				(pts
					(xy 22.86 -78.867) (xy 22.479 -78.867) (xy 22.479 -78.359) (xy 22.86 -78.359)
				)
			)
		)
		(zone
			(layer "F.Cu")
			(hatch none 0.5)
			(connect_pads
				(clearance 0)
			)
			(min_thickness 0.25)
			(keepout
				(tracks not_allowed)
				(vias allowed)
				(pads allowed)
				(copperpour not_allowed)
				(footprints allowed)
			)
			(placement
				(enabled no)
				(sheetname "")
			)
			(fill
				(thermal_gap 0.5)
				(thermal_bridge_width 0.5)
				(island_removal_mode 0)
			)
			(polygon
				(pts
					(xy 22.86 -78.867) (xy 22.479 -78.867) (xy 22.479 -78.359) (xy 22.86 -78.359)
				)
			)
		)
	)
	(footprint ""
		(layer "F.Cu")
		(at 394.6525 -77.597 90)
		(property "Reference" "R7D29"
			(at 0 0 90)
			(layer "F.SilkS")
			(hide yes)
			(effects
				(font
					(size 1.27 1.27)
				)
			)
		)
		(property "Value" ""
			(at 0 0 90)
			(layer "F.Fab")
			(effects
				(font
					(size 1.27 1.27)
				)
			)
		)
		(duplicate_pad_numbers_are_jumpers no)
		(fp_poly
			(pts
				(xy -0.2794 -0.1016) (xy 0.2794 -0.1016) (xy 0.2794 0.9906) (xy -0.2794 0.9906)
			)
			(stroke
				(width 0)
				(type default)
			)
			(fill no)
			(layer "F.CrtYd")
		)
		(fp_line
			(start 0.2794 -0.1016)
			(end -0.2794 -0.1016)
			(stroke
				(width 0.1)
				(type default)
			)
			(layer "F.Fab")
		)
		(fp_line
			(start -0.2794 -0.1016)
			(end -0.2794 0.9906)
			(stroke
				(width 0.1)
				(type default)
			)
			(layer "F.Fab")
		)
		(fp_line
			(start 0.2794 0.9906)
			(end 0.2794 -0.1016)
			(stroke
				(width 0.1)
				(type default)
			)
			(layer "F.Fab")
		)
		(fp_line
			(start -0.2794 0.9906)
			(end 0.2794 0.9906)
			(stroke
				(width 0.1)
				(type default)
			)
			(layer "F.Fab")
		)
		(pad "1" smd rect
			(at 0 0 90)
			(size 0.508 0.508)
			(layers "F.Cu" "F.Mask" "F.Paste")
			(net "FM_CPU0_FIVR_FAULT_R_LVT3")
		)
		(pad "2" smd rect
			(at 0 0.889 90)
			(size 0.508 0.508)
			(layers "F.Cu" "F.Mask" "F.Paste")
			(net "FM_CPU0_FIVR_FAULT_LVT3")
		)
		(zone
			(layer "F.Cu")
			(hatch none 0.5)
			(connect_pads
				(clearance 0)
			)
			(min_thickness 0.25)
			(keepout
				(tracks allowed)
				(vias not_allowed)
				(pads allowed)
				(copperpour not_allowed)
				(footprints allowed)
			)
			(placement
				(enabled no)
				(sheetname "")
			)
			(fill
				(thermal_gap 0.5)
				(thermal_bridge_width 0.5)
				(island_removal_mode 0)
			)
			(polygon
				(pts
					(xy 394.9065 -77.343) (xy 394.9065 -77.851) (xy 395.2875 -77.851) (xy 395.2875 -77.343)
				)
			)
		)
		(zone
			(layer "F.Cu")
			(hatch none 0.5)
			(connect_pads
				(clearance 0)
			)
			(min_thickness 0.25)
			(keepout
				(tracks not_allowed)
				(vias allowed)
				(pads allowed)
				(copperpour not_allowed)
				(footprints allowed)
			)
			(placement
				(enabled no)
				(sheetname "")
			)
			(fill
				(thermal_gap 0.5)
				(thermal_bridge_width 0.5)
				(island_removal_mode 0)
			)
			(polygon
				(pts
					(xy 395.2875 -77.343) (xy 395.2875 -77.851) (xy 394.9065 -77.851) (xy 394.9065 -77.343)
				)
			)
		)
	)
	(footprint ""
		(layer "F.Cu")
		(at 471.507566 -26.299668 180)
		(property "Reference" "C8E14"
			(at 0 0 180)
			(layer "F.SilkS")
			(hide yes)
			(effects
				(font
					(size 1.27 1.27)
				)
			)
		)
		(property "Value" ""
			(at 0 0 180)
			(layer "F.Fab")
			(effects
				(font
					(size 1.27 1.27)
				)
			)
		)
		(duplicate_pad_numbers_are_jumpers no)
		(fp_poly
			(pts
				(xy 0.3048 -0.1016) (xy 0.3048 0.9906) (xy -0.3048 0.9906) (xy -0.3048 -0.1016)
			)
			(stroke
				(width 0)
				(type default)
			)
			(fill no)
			(layer "F.CrtYd")
		)
		(fp_line
			(start 0.3048 0.9906)
			(end 0.3048 -0.1016)
			(stroke
				(width 0.1)
				(type default)
			)
			(layer "F.Fab")
		)
		(fp_line
			(start 0.3048 -0.1016)
			(end -0.3048 -0.1016)
			(stroke
				(width 0.1)
				(type default)
			)
			(layer "F.Fab")
		)
		(fp_line
			(start -0.3048 0.9906)
			(end 0.3048 0.9906)
			(stroke
				(width 0.1)
				(type default)
			)
			(layer "F.Fab")
		)
		(fp_line
			(start -0.3048 -0.1016)
			(end -0.3048 0.9906)
			(stroke
				(width 0.1)
				(type default)
			)
			(layer "F.Fab")
		)
		(pad "1" smd rect
			(at 0 0 180)
			(size 0.508 0.508)
			(layers "F.Cu" "F.Mask" "F.Paste")
			(net "VR_FET_SW_P12V_STBY_P3V3_STBY")
		)
		(pad "2" smd rect
			(at 0 0.889 180)
			(size 0.508 0.508)
			(layers "F.Cu" "F.Mask" "F.Paste")
			(net "GND")
		)
		(zone
			(layer "F.Cu")
			(hatch none 0.5)
			(connect_pads
				(clearance 0)
			)
			(min_thickness 0.25)
			(keepout
				(tracks not_allowed)
				(vias allowed)
				(pads allowed)
				(copperpour not_allowed)
				(footprints allowed)
			)
			(placement
				(enabled no)
				(sheetname "")
			)
			(fill
				(thermal_gap 0.5)
				(thermal_bridge_width 0.5)
				(island_removal_mode 0)
			)
			(polygon
				(pts
					(xy 471.761566 -26.934668) (xy 471.253566 -26.934668) (xy 471.253566 -26.553668) (xy 471.761566 -26.553668)
				)
			)
		)
		(zone
			(layer "F.Cu")
			(hatch none 0.5)
			(connect_pads
				(clearance 0)
			)
			(min_thickness 0.25)
			(keepout
				(tracks allowed)
				(vias not_allowed)
				(pads allowed)
				(copperpour not_allowed)
				(footprints allowed)
			)
			(placement
				(enabled no)
				(sheetname "")
			)
			(fill
				(thermal_gap 0.5)
				(thermal_bridge_width 0.5)
				(island_removal_mode 0)
			)
			(polygon
				(pts
					(xy 471.761566 -26.553668) (xy 471.253566 -26.553668) (xy 471.253566 -26.934668) (xy 471.761566 -26.934668)
				)
			)
		)
	)
	(footprint ""
		(layer "F.Cu")
		(at 466.09 -148.0185 180)
		(property "Reference" "C9A2"
			(at 0 0 180)
			(layer "F.SilkS")
			(hide yes)
			(effects
				(font
					(size 1.27 1.27)
				)
			)
		)
		(property "Value" ""
			(at 0 0 180)
			(layer "F.Fab")
			(effects
				(font
					(size 1.27 1.27)
				)
			)
		)
		(duplicate_pad_numbers_are_jumpers no)
		(fp_poly
			(pts
				(xy 0.3048 -0.1016) (xy 0.3048 0.9906) (xy -0.3048 0.9906) (xy -0.3048 -0.1016)
			)
			(stroke
				(width 0)
				(type default)
			)
			(fill no)
			(layer "F.CrtYd")
		)
		(fp_line
			(start 0.3048 0.9906)
			(end 0.3048 -0.1016)
			(stroke
				(width 0.1)
				(type default)
			)
			(layer "F.Fab")
		)
		(fp_line
			(start 0.3048 -0.1016)
			(end -0.3048 -0.1016)
			(stroke
				(width 0.1)
				(type default)
			)
			(layer "F.Fab")
		)
		(fp_line
			(start -0.3048 0.9906)
			(end 0.3048 0.9906)
			(stroke
				(width 0.1)
				(type default)
			)
			(layer "F.Fab")
		)
		(fp_line
			(start -0.3048 -0.1016)
			(end -0.3048 0.9906)
			(stroke
				(width 0.1)
				(type default)
			)
			(layer "F.Fab")
		)
		(pad "1" smd rect
			(at 0 0 180)
			(size 0.508 0.508)
			(layers "F.Cu" "F.Mask" "F.Paste")
			(net "XDP_SYSPWROK")
		)
		(pad "2" smd rect
			(at 0 0.889 180)
			(size 0.508 0.508)
			(layers "F.Cu" "F.Mask" "F.Paste")
			(net "GND")
		)
		(zone
			(layer "F.Cu")
			(hatch none 0.5)
			(connect_pads
				(clearance 0)
			)
			(min_thickness 0.25)
			(keepout
				(tracks not_allowed)
				(vias allowed)
				(pads allowed)
				(copperpour not_allowed)
				(footprints allowed)
			)
			(placement
				(enabled no)
				(sheetname "")
			)
			(fill
				(thermal_gap 0.5)
				(thermal_bridge_width 0.5)
				(island_removal_mode 0)
			)
			(polygon
				(pts
					(xy 466.344 -148.6535) (xy 465.836 -148.6535) (xy 465.836 -148.2725) (xy 466.344 -148.2725)
				)
			)
		)
		(zone
			(layer "F.Cu")
			(hatch none 0.5)
			(connect_pads
				(clearance 0)
			)
			(min_thickness 0.25)
			(keepout
				(tracks allowed)
				(vias not_allowed)
				(pads allowed)
				(copperpour not_allowed)
				(footprints allowed)
			)
			(placement
				(enabled no)
				(sheetname "")
			)
			(fill
				(thermal_gap 0.5)
				(thermal_bridge_width 0.5)
				(island_removal_mode 0)
			)
			(polygon
				(pts
					(xy 466.344 -148.2725) (xy 465.836 -148.2725) (xy 465.836 -148.6535) (xy 466.344 -148.6535)
				)
			)
		)
	)
	(footprint ""
		(layer "F.Cu")
		(at 165.481 -70.6374 180)
		(property "Reference" "C4D33"
			(at 0 0 180)
			(layer "F.SilkS")
			(hide yes)
			(effects
				(font
					(size 1.27 1.27)
				)
			)
		)
		(property "Value" ""
			(at 0 0 180)
			(layer "F.Fab")
			(effects
				(font
					(size 1.27 1.27)
				)
			)
		)
		(duplicate_pad_numbers_are_jumpers no)
		(fp_poly
			(pts
				(xy 0.3048 -0.1016) (xy 0.3048 0.9906) (xy -0.3048 0.9906) (xy -0.3048 -0.1016)
			)
			(stroke
				(width 0)
				(type default)
			)
			(fill no)
			(layer "F.CrtYd")
		)
		(fp_line
			(start 0.3048 0.9906)
			(end 0.3048 -0.1016)
			(stroke
				(width 0.1)
				(type default)
			)
			(layer "F.Fab")
		)
		(fp_line
			(start 0.3048 -0.1016)
			(end -0.3048 -0.1016)
			(stroke
				(width 0.1)
				(type default)
			)
			(layer "F.Fab")
		)
		(fp_line
			(start -0.3048 0.9906)
			(end 0.3048 0.9906)
			(stroke
				(width 0.1)
				(type default)
			)
			(layer "F.Fab")
		)
		(fp_line
			(start -0.3048 -0.1016)
			(end -0.3048 0.9906)
			(stroke
				(width 0.1)
				(type default)
			)
			(layer "F.Fab")
		)
		(pad "1" smd rect
			(at 0 0 180)
			(size 0.508 0.508)
			(layers "F.Cu" "F.Mask" "F.Paste")
			(net "PWRGD_PVCCIO_CPU1_R")
		)
		(pad "2" smd rect
			(at 0 0.889 180)
			(size 0.508 0.508)
			(layers "F.Cu" "F.Mask" "F.Paste")
			(net "GND")
		)
		(zone
			(layer "F.Cu")
			(hatch none 0.5)
			(connect_pads
				(clearance 0)
			)
			(min_thickness 0.25)
			(keepout
				(tracks not_allowed)
				(vias allowed)
				(pads allowed)
				(copperpour not_allowed)
				(footprints allowed)
			)
			(placement
				(enabled no)
				(sheetname "")
			)
			(fill
				(thermal_gap 0.5)
				(thermal_bridge_width 0.5)
				(island_removal_mode 0)
			)
			(polygon
				(pts
					(xy 165.735 -71.2724) (xy 165.227 -71.2724) (xy 165.227 -70.8914) (xy 165.735 -70.8914)
				)
			)
		)
		(zone
			(layer "F.Cu")
			(hatch none 0.5)
			(connect_pads
				(clearance 0)
			)
			(min_thickness 0.25)
			(keepout
				(tracks allowed)
				(vias not_allowed)
				(pads allowed)
				(copperpour not_allowed)
				(footprints allowed)
			)
			(placement
				(enabled no)
				(sheetname "")
			)
			(fill
				(thermal_gap 0.5)
				(thermal_bridge_width 0.5)
				(island_removal_mode 0)
			)
			(polygon
				(pts
					(xy 165.735 -70.8914) (xy 165.227 -70.8914) (xy 165.227 -71.2724) (xy 165.735 -71.2724)
				)
			)
		)
	)
	(footprint ""
		(layer "F.Cu")
		(at 151.892 -120.142 -90)
		(property "Reference" "C3B6"
			(at 3.20167 3.81 0)
			(unlocked yes)
			(layer "F.SilkS")
			(effects
				(font
					(size 0.7874 0.5842)
					(thickness 0.1524)
				)
			)
		)
		(property "Value" ""
			(at 0 0 270)
			(layer "F.Fab")
			(effects
				(font
					(size 1.27 1.27)
				)
			)
		)
		(duplicate_pad_numbers_are_jumpers no)
		(fp_line
			(start -2.286 7.366)
			(end -1.60147 7.366)
			(stroke
				(width 0.1524)
				(type default)
			)
			(layer "F.SilkS")
		)
		(fp_line
			(start -2.286 7.366)
			(end -2.286 1.632712)
			(stroke
				(width 0.1524)
				(type default)
			)
			(layer "F.SilkS")
		)
		(fp_line
			(start 2.286 7.366)
			(end 1.600708 7.366)
			(stroke
				(width 0.1524)
				(type default)
			)
			(layer "F.SilkS")
		)
		(fp_line
			(start 2.286 7.366)
			(end 2.286 1.63195)
			(stroke
				(width 0.1524)
				(type default)
			)
			(layer "F.SilkS")
		)
		(fp_line
			(start -2.563114 1.633728)
			(end -1.6002 1.633728)
			(stroke
				(width 0.1524)
				(type default)
			)
			(layer "F.SilkS")
		)
		(fp_line
			(start 2.504948 1.633728)
			(end 1.6002 1.633728)
			(stroke
				(width 0.1524)
				(type default)
			)
			(layer "F.SilkS")
		)
		(fp_line
			(start -2.563114 -1.616456)
			(end -2.563114 1.633728)
			(stroke
				(width 0.1524)
				(type default)
			)
			(layer "F.SilkS")
		)
		(fp_line
			(start -1.6002 -1.616456)
			(end -2.563114 -1.616456)
			(stroke
				(width 0.1524)
				(type default)
			)
			(layer "F.SilkS")
		)
		(fp_line
			(start 1.6002 -1.616456)
			(end 2.504948 -1.616456)
			(stroke
				(width 0.1524)
				(type default)
			)
			(layer "F.SilkS")
		)
		(fp_line
			(start 2.504948 -1.616456)
			(end 2.504948 1.633728)
			(stroke
				(width 0.1524)
				(type default)
			)
			(layer "F.SilkS")
		)
		(fp_rect
			(start -2.286 7.366)
			(end 2.286 -0.254)
			(stroke
				(width 0)
				(type default)
			)
			(fill no)
			(layer "F.CrtYd")
		)
		(fp_line
			(start -2.286 7.366)
			(end -2.286 -0.254)
			(stroke
				(width 0.1)
				(type default)
			)
			(layer "F.Fab")
		)
		(fp_line
			(start 2.286 7.366)
			(end -2.286 7.366)
			(stroke
				(width 0.1)
				(type default)
			)
			(layer "F.Fab")
		)
		(fp_line
			(start -2.286 -0.254)
			(end 2.286 -0.254)
			(stroke
				(width 0.1)
				(type default)
			)
			(layer "F.Fab")
		)
		(fp_line
			(start 2.286 -0.254)
			(end 2.286 7.366)
			(stroke
				(width 0.1)
				(type default)
			)
			(layer "F.Fab")
		)
		(pad "1" smd rect
			(at 0 0 270)
			(size 2.54 3.048)
			(layers "F.Cu" "F.Mask" "F.Paste")
			(net "P12V_STBY")
		)
		(pad "2" smd rect
			(at 0 7.112 270)
			(size 2.54 3.048)
			(layers "F.Cu" "F.Mask" "F.Paste")
			(net "GND")
		)
	)
)
